# T6G (Grand Teton) — schematic netlist excerpt (pin names and nets, part order shuffled) for the footprints in the layout excerpt that follows; sources: Cadence DE-HDL packaged netlist, KiCad conversion of 04192023_DAF0TMB3IC0_F0TG_MB_C_brd_V02_OCP.brd

C426  Q_CAP  0.1UF 10V 10% X7S  pkg C0201  page 345 : A = P0V9_CPU1_RT2_2A ; B = GND
C6085  Q_CAP  0.1UF 25V 10% EMPTY  pkg 0402  page 270 : A = PWRGD_P1V8_AUX_R ; B = GND
R2666  Q_RES  10K 1% CHIP  pkg 0402LF  page 248 : A = SMB_BMC_SWB_EN ; B = GND

(kicad_pcb
	(version 20260206)
	(generator "pcbnew")
	(generator_version "10.0")
	(general
		(thickness 1.6)
		(legacy_teardrops no)
	)
	(paper "A4")
	(title_block
		(title "04192023_DAF0TMB3IC0_F0TG_MB_C_brd_V02_OCP.brd")
		(comment 1 "Grand Teton / footprints 7615-7617 of 8354")
	)
	(layers
		(0 "F.Cu" signal "TOP")
		(4 "In1.Cu" signal "GND")
		(6 "In2.Cu" signal "IN1")
		(8 "In3.Cu" signal "GND1")
		(10 "In4.Cu" signal "IN2")
		(12 "In5.Cu" signal "GND2")
		(14 "In6.Cu" signal "IN3")
		(16 "In7.Cu" signal "GND3")
		(18 "In8.Cu" signal "VCC")
		(20 "In9.Cu" signal "VCC1")
		(22 "In10.Cu" signal "GND4")
		(24 "In11.Cu" signal "IN4")
		(26 "In12.Cu" signal "GND5")
		(28 "In13.Cu" signal "IN5")
		(30 "In14.Cu" signal "GND6")
		(32 "In15.Cu" signal "IN6")
		(34 "In16.Cu" signal "GND7")
		(2 "B.Cu" signal "BOTTOM")
		(9 "F.Adhes" user "F.Adhesive")
		(11 "B.Adhes" user "B.Adhesive")
		(13 "F.Paste" user "Package Geometry/Pastemask Top")
		(15 "B.Paste" user "Package Geometry/Pastemask Bottom")
		(5 "F.SilkS" user "Ref Des/Silkscreen Top")
		(7 "B.SilkS" user "Ref Des/Silkscreen Bottom")
		(1 "F.Mask" user "Board Geometry/Soldermask Top")
		(3 "B.Mask" user "Board Geometry/Soldermask Bottom")
		(17 "Dwgs.User" user "User.Drawings")
		(19 "Cmts.User" user "User.Comments")
		(21 "Eco1.User" user "User.Eco1")
		(23 "Eco2.User" user "User.Eco2")
		(25 "Edge.Cuts" user "Board Geometry/Outline")
		(27 "Margin" user)
		(31 "F.CrtYd" user "Package Geometry/Place Bound Top")
		(29 "B.CrtYd" user "Package Geometry/Place Bound Bottom")
		(35 "F.Fab" user "Ref Des/Assembly Top")
		(33 "B.Fab" user "Ref Des/Assembly Bottom")
	)
	(footprint ""
		(layer "B.Cu")
		(at 121.810272 -71.397622 180)
		(property "Reference" "C6085"
			(at 0 0 0)
			(layer "B.SilkS")
			(hide yes)
			(effects
				(font
					(size 1.27 1.27)
				)
				(justify mirror)
			)
		)
		(property "Value" ""
			(at 0 0 0)
			(layer "B.Fab")
			(effects
				(font
					(size 1.27 1.27)
				)
				(justify mirror)
			)
		)
		(duplicate_pad_numbers_are_jumpers no)
		(fp_line
			(start 0.7874 0.4064)
			(end 0.7874 -0.4064)
			(stroke
				(width 0.1524)
				(type default)
			)
			(layer "B.SilkS")
		)
		(fp_line
			(start 0.7874 -0.4064)
			(end -0.7874 -0.4064)
			(stroke
				(width 0.1524)
				(type default)
			)
			(layer "B.SilkS")
		)
		(fp_line
			(start -0.7874 0.4064)
			(end 0.7874 0.4064)
			(stroke
				(width 0.1524)
				(type default)
			)
			(layer "B.SilkS")
		)
		(fp_line
			(start -0.7874 -0.4064)
			(end -0.7874 0.4064)
			(stroke
				(width 0.1524)
				(type default)
			)
			(layer "B.SilkS")
		)
		(fp_line
			(start 0.67945 0.3048)
			(end 0.67945 -0.305054)
			(stroke
				(width 0.1)
				(type default)
			)
			(layer "B.Fab")
		)
		(fp_line
			(start 0.67945 -0.305054)
			(end 0.12065 -0.305054)
			(stroke
				(width 0.1)
				(type default)
			)
			(layer "B.Fab")
		)
		(fp_line
			(start 0.12065 0.3048)
			(end 0.67945 0.3048)
			(stroke
				(width 0.1)
				(type default)
			)
			(layer "B.Fab")
		)
		(fp_line
			(start 0.12065 0.2794)
			(end 0.12065 0.3048)
			(stroke
				(width 0.1)
				(type default)
			)
			(layer "B.Fab")
		)
		(fp_line
			(start 0.12065 -0.2794)
			(end -0.12065 -0.2794)
			(stroke
				(width 0.1)
				(type default)
			)
			(layer "B.Fab")
		)
		(fp_line
			(start 0.12065 -0.305054)
			(end 0.12065 -0.2794)
			(stroke
				(width 0.1)
				(type default)
			)
			(layer "B.Fab")
		)
		(fp_line
			(start -0.120396 0.3048)
			(end -0.120396 0.2794)
			(stroke
				(width 0.1)
				(type default)
			)
			(layer "B.Fab")
		)
		(fp_line
			(start -0.120396 0.2794)
			(end 0.12065 0.2794)
			(stroke
				(width 0.1)
				(type default)
			)
			(layer "B.Fab")
		)
		(fp_line
			(start -0.12065 -0.2794)
			(end -0.12065 -0.3048)
			(stroke
				(width 0.1)
				(type default)
			)
			(layer "B.Fab")
		)
		(fp_line
			(start -0.12065 -0.3048)
			(end -0.67945 -0.3048)
			(stroke
				(width 0.1)
				(type default)
			)
			(layer "B.Fab")
		)
		(fp_line
			(start -0.67945 0.3048)
			(end -0.120396 0.3048)
			(stroke
				(width 0.1)
				(type default)
			)
			(layer "B.Fab")
		)
		(fp_line
			(start -0.67945 -0.3048)
			(end -0.67945 0.3048)
			(stroke
				(width 0.1)
				(type default)
			)
			(layer "B.Fab")
		)
		(pad "1" smd circle
			(at 0.40005 0)
			(size 0 0)
			(layers "B.Cu" "B.Mask" "B.Paste")
			(net "PWRGD_P1V8_AUX_R")
		)
		(pad "2" smd circle
			(at -0.40005 0)
			(size 0 0)
			(layers "B.Cu" "B.Mask" "B.Paste")
			(net "GND")
		)
	)
	(footprint ""
		(layer "B.Cu")
		(at 287.149286 -428.26051)
		(property "Reference" "R2666"
			(at 0 0 0)
			(layer "B.SilkS")
			(hide yes)
			(effects
				(font
					(size 1.27 1.27)
				)
				(justify mirror)
			)
		)
		(property "Value" ""
			(at 0 0 0)
			(layer "B.Fab")
			(effects
				(font
					(size 1.27 1.27)
				)
				(justify mirror)
			)
		)
		(duplicate_pad_numbers_are_jumpers no)
		(fp_line
			(start -0.7874 -0.4064)
			(end -0.7874 0.4064)
			(stroke
				(width 0.1524)
				(type default)
			)
			(layer "B.SilkS")
		)
		(fp_line
			(start -0.7874 0.4064)
			(end 0.7874 0.4064)
			(stroke
				(width 0.1524)
				(type default)
			)
			(layer "B.SilkS")
		)
		(fp_line
			(start 0.7874 -0.4064)
			(end -0.7874 -0.4064)
			(stroke
				(width 0.1524)
				(type default)
			)
			(layer "B.SilkS")
		)
		(fp_line
			(start 0.7874 0.4064)
			(end 0.7874 -0.4064)
			(stroke
				(width 0.1524)
				(type default)
			)
			(layer "B.SilkS")
		)
		(fp_line
			(start -0.67945 -0.3048)
			(end -0.67945 0.3048)
			(stroke
				(width 0.1)
				(type default)
			)
			(layer "B.Fab")
		)
		(fp_line
			(start -0.67945 0.3048)
			(end -0.120396 0.3048)
			(stroke
				(width 0.1)
				(type default)
			)
			(layer "B.Fab")
		)
		(fp_line
			(start -0.12065 -0.3048)
			(end -0.67945 -0.3048)
			(stroke
				(width 0.1)
				(type default)
			)
			(layer "B.Fab")
		)
		(fp_line
			(start -0.12065 -0.2794)
			(end -0.12065 -0.3048)
			(stroke
				(width 0.1)
				(type default)
			)
			(layer "B.Fab")
		)
		(fp_line
			(start -0.120396 0.2794)
			(end 0.12065 0.2794)
			(stroke
				(width 0.1)
				(type default)
			)
			(layer "B.Fab")
		)
		(fp_line
			(start -0.120396 0.3048)
			(end -0.120396 0.2794)
			(stroke
				(width 0.1)
				(type default)
			)
			(layer "B.Fab")
		)
		(fp_line
			(start 0.12065 -0.305054)
			(end 0.12065 -0.2794)
			(stroke
				(width 0.1)
				(type default)
			)
			(layer "B.Fab")
		)
		(fp_line
			(start 0.12065 -0.2794)
			(end -0.12065 -0.2794)
			(stroke
				(width 0.1)
				(type default)
			)
			(layer "B.Fab")
		)
		(fp_line
			(start 0.12065 0.2794)
			(end 0.12065 0.3048)
			(stroke
				(width 0.1)
				(type default)
			)
			(layer "B.Fab")
		)
		(fp_line
			(start 0.12065 0.3048)
			(end 0.67945 0.3048)
			(stroke
				(width 0.1)
				(type default)
			)
			(layer "B.Fab")
		)
		(fp_line
			(start 0.67945 -0.305054)
			(end 0.12065 -0.305054)
			(stroke
				(width 0.1)
				(type default)
			)
			(layer "B.Fab")
		)
		(fp_line
			(start 0.67945 0.3048)
			(end 0.67945 -0.305054)
			(stroke
				(width 0.1)
				(type default)
			)
			(layer "B.Fab")
		)
		(pad "1" smd circle
			(at 0.40005 0 180)
			(size 0 0)
			(layers "B.Cu" "B.Mask" "B.Paste")
			(net "SMB_BMC_SWB_EN")
		)
		(pad "2" smd circle
			(at -0.40005 0 180)
			(size 0 0)
			(layers "B.Cu" "B.Mask" "B.Paste")
			(net "GND")
		)
	)
	(footprint ""
		(layer "B.Cu")
		(at 165.08984 -384.29946 -90)
		(property "Reference" "C426"
			(at 0 0 90)
			(layer "B.SilkS")
			(hide yes)
			(effects
				(font
					(size 1.27 1.27)
				)
				(justify mirror)
			)
		)
		(property "Value" ""
			(at 0 0 90)
			(layer "B.Fab")
			(effects
				(font
					(size 1.27 1.27)
				)
				(justify mirror)
			)
		)
		(duplicate_pad_numbers_are_jumpers no)
		(fp_line
			(start -0.299974 0.150114)
			(end 0.299974 0.150114)
			(stroke
				(width 0.1)
				(type default)
			)
			(layer "B.Fab")
		)
		(fp_line
			(start 0.299974 0.150114)
			(end 0.299974 -0.150114)
			(stroke
				(width 0.1)
				(type default)
			)
			(layer "B.Fab")
		)
		(fp_line
			(start -0.299974 -0.150114)
			(end -0.299974 0.150114)
			(stroke
				(width 0.1)
				(type default)
			)
			(layer "B.Fab")
		)
		(fp_line
			(start 0.299974 -0.150114)
			(end -0.299974 -0.150114)
			(stroke
				(width 0.1)
				(type default)
			)
			(layer "B.Fab")
		)
		(pad "1" smd rect
			(at 0.2667 0 90)
			(size 0.3048 0.381)
			(layers "B.Cu" "B.Mask" "B.Paste")
			(net "P0V9_CPU1_RT2_2A")
		)
		(pad "2" smd rect
			(at -0.2667 0 90)
			(size 0.3048 0.381)
			(layers "B.Cu" "B.Mask" "B.Paste")
			(net "GND")
		)
	)
)
